# BASEBOARD_FAB2 (Tioga Pass) — schematic netlist excerpt (pin names and nets, part order shuffled) for the footprints in the layout excerpt that follows; sources: Cadence DE-HDL packaged netlist, KiCad conversion of Wiwynn_Tioga_Pass_MB.brd

J1G2  SCONN288_H44441004  SCONN  pkg PIP  page 79
  \12v\(1)  = P12V_NVDIMM_GHJ
  VSS(93)  = GND
  DQ(4)  = M_H_DQ<5>
  VSS(92)  = GND
  DQ(0)  = M_H_DQ<1>
  VSS(91)  = GND
  DQS9P  = M_H_DQS_DP<9>
  DQS9N  = M_H_DQS_DN<9>
  VSS(90)  = GND
  DQ(6)  = M_H_DQ<7>
  VSS(89)  = GND
  DQ(2)  = M_H_DQ<3>
  VSS(88)  = GND
  DQ(12)  = M_H_DQ<13>
  VSS(87)  = GND
  DQ(8)  = M_H_DQ<9>
  VSS(86)  = GND
  DQS10P  = M_H_DQS_DP<10>
  DQS10N  = M_H_DQS_DN<10>
  VSS(85)  = GND
  DQ(14)  = M_H_DQ<15>
  VSS(84)  = GND
  DQ(10)  = M_H_DQ<11>
  VSS(83)  = GND
  DQ(20)  = M_H_DQ<21>
  VSS(82)  = GND
  DQ(16)  = M_H_DQ<17>
  VSS(81)  = GND
  DQS11P  = M_H_DQS_DP<11>
  DQS11N  = M_H_DQS_DN<11>
  VSS(80)  = GND
  DQ(22)  = M_H_DQ<23>
  VSS(79)  = GND
  DQ(18)  = M_H_DQ<19>
  VSS(78)  = GND
  DQ(28)  = M_H_DQ<29>
  VSS(77)  = GND
  DQ(24)  = M_H_DQ<25>
  VSS(76)  = GND
  DQS12P  = M_H_DQS_DP<12>
  DQS12N  = M_H_DQS_DN<12>
  VSS(75)  = GND
  DQ(30)  = M_H_DQ<31>
  VSS(74)  = GND
  DQ(26)  = M_H_DQ<27>
  VSS(73)  = GND
  CB(4)  = M_H_ECC<5>
  VSS(72)  = GND
  CB(0)  = M_H_ECC<1>
  VSS(71)  = GND
  DQS17P  = M_H_DQS_DP<17>
  DQS17N  = M_H_DQS_DN<17>
  VSS(70)  = GND
  CB(6)  = M_H_ECC<7>
  VSS(69)  = GND
  CB(2)  = M_H_ECC<3>
  VSS(68)  = GND
  RESET_N  = M_GHJ_RST_N
  VDD(25)  = PVDDQ_GHJ
  CKE(0)  = M_H_CKE<0>
  VDD(24)  = PVDDQ_GHJ
  ACT_N  = M_H_ACT_N
  BG(0)  = M_H_BG<0>
  VDD(23)  = PVDDQ_GHJ
  A12  = M_H_MA<12>
  A9  = M_H_MA<9>
  VDD(22)  = PVDDQ_GHJ
  A8  = M_H_MA<8>
  A6  = M_H_MA<6>
  VDD(21)  = PVDDQ_GHJ
  A3  = M_H_MA<3>
  A1  = M_H_MA<1>
  VDD(20)  = PVDDQ_GHJ
  CK0P  = M_H_CLK_DP<0>
  CK0N  = M_H_CLK_DN<0>
  VDD(19)  = PVDDQ_GHJ
  VTT(1)  = PVTT_GHJ
  EVENT_N  = FM_DIMM_EVENT_COD_N
  A0  = M_H_MA<0>
  VDD(18)  = PVDDQ_GHJ
  BA(0)  = M_H_BA<0>
  A16_RAS_N  = M_H_MA<16>
  VDD(17)  = PVDDQ_GHJ
  S0_N  = M_H_CS_N<0>
  VDD(16)  = PVDDQ_GHJ
  A15_CAS_N  = M_H_MA<15>
  ODT(0)  = M_H_ODT<0>
  VDD(15)  = PVDDQ_GHJ
  S1_N  = M_H_CS_N<1>
  VDD(14)  = PVDDQ_GHJ
  ODT(1)  = M_H_ODT<1>
  VDD(13)  = PVDDQ_GHJ
  S2_N_C(0)  = M_H_CS_N<2>
  VSS(67)  = GND
  DQ(36)  = M_H_DQ<37>
  VSS(66)  = GND
  DQ(32)  = M_H_DQ<33>
  VSS(65)  = GND
  DQS13P  = M_H_DQS_DP<13>
  DQS13N  = M_H_DQS_DN<13>
  VSS(64)  = GND
  DQ(38)  = M_H_DQ<39>
  VSS(63)  = GND
  DQ(34)  = M_H_DQ<35>
  VSS(62)  = GND
  DQ(44)  = M_H_DQ<45>
  VSS(61)  = GND
  DQ(40)  = M_H_DQ<41>
  VSS(60)  = GND
  DQS14P  = M_H_DQS_DP<14>
  DQS14N  = M_H_DQS_DN<14>
  VSS(59)  = GND
  DQ(46)  = M_H_DQ<47>
  VSS(58)  = GND
  DQ(42)  = M_H_DQ<43>
  VSS(57)  = GND
  DQ(52)  = M_H_DQ<53>
  VSS(56)  = GND
  DQ(48)  = M_H_DQ<49>
  VSS(55)  = GND
  DQS15P  = M_H_DQS_DP<15>
  DQS15N  = M_H_DQS_DN<15>
  VSS(54)  = GND
  DQ(54)  = M_H_DQ<55>
  VSS(53)  = GND
  DQ(50)  = M_H_DQ<51>
  VSS(52)  = GND
  DQ(60)  = M_H_DQ<61>
  VSS(51)  = GND
  DQ(56)  = M_H_DQ<57>
  VSS(50)  = GND
  DQS16P  = M_H_DQS_DP<16>
  DQS16N  = M_H_DQS_DN<16>
  VSS(49)  = GND
  DQ(62)  = M_H_DQ<63>
  VSS(48)  = GND
  DQ(58)  = M_H_DQ<59>
  VSS(47)  = GND
  SA(0)  = GND
  SA(1)  = PVPP_GHJ
  SCL  = SMB_DDR_GHJ_VPP_SCL
  VPP(4)  = PVPP_GHJ
  VPP(3)  = PVPP_GHJ
  RFU(2)  = TP_CH_H_DIMM_H0_RFU_2
  \12v\(0)  = P12V_NVDIMM_GHJ
  VREFCA  = M_H_VREF
  VSS(46)  = GND
  DQ(5)  = M_H_DQ<4>
  VSS(45)  = GND
  DQ(1)  = M_H_DQ<0>
  VSS(44)  = GND
  DQS0N  = M_H_DQS_DN<0>
  DQS0P  = M_H_DQS_DP<0>
  VSS(43)  = GND
  DQ(7)  = M_H_DQ<6>
  VSS(42)  = GND
  DQ(3)  = M_H_DQ<2>
  VSS(41)  = GND
  DQ(13)  = M_H_DQ<12>
  VSS(40)  = GND
  DQ(9)  = M_H_DQ<8>
  VSS(39)  = GND
  DQS1N  = M_H_DQS_DN<1>
  DQS1P  = M_H_DQS_DP<1>
  VSS(38)  = GND
  DQ(15)  = M_H_DQ<14>
  VSS(37)  = GND
  DQ(11)  = M_H_DQ<10>
  VSS(36)  = GND
  DQ(21)  = M_H_DQ<20>
  VSS(35)  = GND
  DQ(17)  = M_H_DQ<16>
  VSS(34)  = GND
  DQS2N  = M_H_DQS_DN<2>
  DQS2P  = M_H_DQS_DP<2>
  VSS(33)  = GND
  DQ(23)  = M_H_DQ<22>
  VSS(32)  = GND
  DQ(19)  = M_H_DQ<18>
  VSS(31)  = GND
  DQ(29)  = M_H_DQ<28>
  VSS(30)  = GND
  DQ(25)  = M_H_DQ<24>
  VSS(29)  = GND
  DQS3N  = M_H_DQS_DN<3>
  DQS3P  = M_H_DQS_DP<3>
  VSS(28)  = GND
  DQ(31)  = M_H_DQ<30>
  VSS(27)  = GND
  DQ(27)  = M_H_DQ<26>
  VSS(26)  = GND
  CB(5)  = M_H_ECC<4>
  VSS(25)  = GND
  CB(1)  = M_H_ECC<0>
  VSS(24)  = GND
  DQS8N  = M_H_DQS_DN<8>
  DQS8P  = M_H_DQS_DP<8>
  VSS(23)  = GND
  CB(7)  = M_H_ECC<6>
  VSS(22)  = GND
  CB(3)  = M_H_ECC<2>
  VSS(21)  = GND
  CKE(1)  = M_H_CKE<1>
  VDD(12)  = PVDDQ_GHJ
  RFU(0)  = TP_CH_H_DIMM_H0_RFU_0
  VDD(11)  = PVDDQ_GHJ
  BG(1)  = M_H_BG<1>
  ALERT_N  = M_H_ALERT_N
  VDD(10)  = PVDDQ_GHJ
  A11  = M_H_MA<11>
  A7  = M_H_MA<7>
  VDD(9)  = PVDDQ_GHJ
  A5  = M_H_MA<5>
  A4  = M_H_MA<4>
  VDD(8)  = PVDDQ_GHJ
  A2  = M_H_MA<2>
  VDD(7)  = PVDDQ_GHJ
  CK1P  = M_H_CLK_DP<1>
  CK1N  = M_H_CLK_DN<1>
  VDD(6)  = PVDDQ_GHJ
  VTT(0)  = PVTT_GHJ
  PAR  = M_H_PAR
  VDD(5)  = PVDDQ_GHJ
  BA(1)  = M_H_BA<1>
  A10  = M_H_MA<10>
  VDD(4)  = PVDDQ_GHJ
  RFU(1)  = TP_CH_H_DIMM_H0_RFU_1
  A14_WE_N  = M_H_MA<14>
  VDD(3)  = PVDDQ_GHJ
  SAVE_N_NC  = FM_ADR_COMPLETE_GHJ_N
  VDD(2)  = PVDDQ_GHJ
  A13  = M_H_MA<13>
  VDD(1)  = PVDDQ_GHJ
  A17  = M_H_MA<17>
  C(2)  = M_H_C<2>
  VDD(0)  = PVDDQ_GHJ
  S3_N_C(1)  = M_H_CS_N<3>
  SA(2)  = GND
  VSS(20)  = GND
  DQ(37)  = M_H_DQ<36>
  VSS(19)  = GND
  DQ(33)  = M_H_DQ<32>
  VSS(18)  = GND
  DQS4N  = M_H_DQS_DN<4>
  DQS4P  = M_H_DQS_DP<4>
  VSS(17)  = GND
  DQ(39)  = M_H_DQ<38>
  VSS(16)  = GND
  DQ(35)  = M_H_DQ<34>
  VSS(15)  = GND
  DQ(45)  = M_H_DQ<44>
  VSS(14)  = GND
  DQ(41)  = M_H_DQ<40>
  VSS(13)  = GND
  DQS5N  = M_H_DQS_DN<5>
  DQS5P  = M_H_DQS_DP<5>
  VSS(12)  = GND
  DQ(47)  = M_H_DQ<46>
  VSS(11)  = GND
  DQ(43)  = M_H_DQ<42>
  VSS(10)  = GND
  DQ(53)  = M_H_DQ<52>
  VSS(9)  = GND
  DQ(49)  = M_H_DQ<48>
  VSS(8)  = GND
  DQS6N  = M_H_DQS_DN<6>
  DQS6P  = M_H_DQS_DP<6>
  VSS(7)  = GND
  DQ(55)  = M_H_DQ<54>
  VSS(6)  = GND
  DQ(51)  = M_H_DQ<50>
  VSS(5)  = GND
  DQ(61)  = M_H_DQ<60>
  VSS(4)  = GND
  DQ(57)  = M_H_DQ<56>
  VSS(3)  = GND
  DQS7N  = M_H_DQS_DN<7>
  DQS7P  = M_H_DQS_DP<7>
  VSS(2)  = GND
  DQ(63)  = M_H_DQ<62>
  VSS(1)  = GND
  DQ(59)  = M_H_DQ<58>
  VSS(0)  = GND
  VDDSPD  = PVPP_GHJ
  SDA  = SMB_DDR_GHJ_VPP_SDA
  VPP(1)  = PVPP_GHJ
  VPP(0)  = PVPP_GHJ
  VPP(2)  = PVPP_GHJ

(kicad_pcb
	(version 20260206)
	(generator "pcbnew")
	(generator_version "10.0")
	(general
		(thickness 1.6)
		(legacy_teardrops no)
	)
	(paper "A4")
	(title_block
		(title "Wiwynn_Tioga_Pass_MB.brd")
		(comment 1 "Tioga Pass / footprint 2141 of 4770 (J1G2), pads 202-249 of 291")
	)
	(layers
		(0 "F.Cu" signal "TOP")
		(4 "In1.Cu" signal "L2GND")
		(6 "In2.Cu" signal "L3")
		(8 "In3.Cu" signal "L4GND")
		(10 "In4.Cu" signal "L5")
		(12 "In5.Cu" signal "L6GND")
		(14 "In6.Cu" signal "L7VCC")
		(16 "In7.Cu" signal "L8VCC")
		(18 "In8.Cu" signal "L9GND")
		(20 "In9.Cu" signal "L10")
		(22 "In10.Cu" signal "L11GND")
		(24 "In11.Cu" signal "L12")
		(26 "In12.Cu" signal "L13GND")
		(2 "B.Cu" signal "BOTTOM")
		(9 "F.Adhes" user "F.Adhesive")
		(11 "B.Adhes" user "B.Adhesive")
		(13 "F.Paste" user "Package Geometry/Pastemask Top")
		(15 "B.Paste" user "Package Geometry/Pastemask Bottom")
		(5 "F.SilkS" user "Ref Des/Silkscreen Top")
		(7 "B.SilkS" user "Ref Des/Silkscreen Bottom")
		(1 "F.Mask" user "Board Geometry/Soldermask Top")
		(3 "B.Mask" user "Board Geometry/Soldermask Bottom")
		(17 "Dwgs.User" user "User.Drawings")
		(19 "Cmts.User" user "User.Comments")
		(21 "Eco1.User" user "User.Eco1")
		(23 "Eco2.User" user "User.Eco2")
		(25 "Edge.Cuts" user "Board Geometry/Outline")
		(27 "Margin" user)
		(31 "F.CrtYd" user "Package Geometry/Place Bound Top")
		(29 "B.CrtYd" user "Package Geometry/Place Bound Bottom")
		(35 "F.Fab" user "Ref Des/Assembly Top")
		(33 "B.Fab" user "Ref Des/Assembly Bottom")
	)
	(footprint ""
		(layer "F.Cu")
		(at 29.699458 -5.822442 90)
		(property "Reference" "J1G2"
			(at 7.104888 34.562542 0)
			(unlocked yes)
			(layer "F.SilkS")
			(effects
				(font
					(size 0.7874 0.5842)
					(thickness 0.1524)
				)
				(justify left)
			)
		)
		(property "Value" ""
			(at 0 0 90)
			(layer "F.Fab")
			(effects
				(font
					(size 1.27 1.27)
				)
			)
		)
		(duplicate_pad_numbers_are_jumpers no)
		(pad "199" smd rect
			(at 4.59994 45.900086 90)
			(size 1.8034 0.508)
			(layers "F.Cu" "F.Mask" "F.Paste")
			(net "M_H_ECC<6>")
		)
		(pad "200" smd rect
			(at 4.59994 46.74997 90)
			(size 1.8034 0.508)
			(layers "F.Cu" "F.Mask" "F.Paste")
			(net "GND")
		)
		(pad "201" smd rect
			(at 4.59994 47.600108 90)
			(size 1.8034 0.508)
			(layers "F.Cu" "F.Mask" "F.Paste")
			(net "M_H_ECC<2>")
		)
		(pad "202" smd rect
			(at 4.59994 48.449992 90)
			(size 1.8034 0.508)
			(layers "F.Cu" "F.Mask" "F.Paste")
			(net "GND")
		)
		(pad "203" smd rect
			(at 4.59994 49.299876 90)
			(size 1.8034 0.508)
			(layers "F.Cu" "F.Mask" "F.Paste")
			(net "M_H_CKE<1>")
		)
		(pad "204" smd rect
			(at 4.59994 50.150014 90)
			(size 1.8034 0.508)
			(layers "F.Cu" "F.Mask" "F.Paste")
			(net "PVDDQ_GHJ")
		)
		(pad "205" smd rect
			(at 4.59994 50.999898 90)
			(size 1.8034 0.508)
			(layers "F.Cu" "F.Mask" "F.Paste")
			(net "TP_CH_H_DIMM_H0_RFU_0")
		)
		(pad "206" smd rect
			(at 4.59994 51.850036 90)
			(size 1.8034 0.508)
			(layers "F.Cu" "F.Mask" "F.Paste")
			(net "PVDDQ_GHJ")
		)
		(pad "207" smd rect
			(at 4.59994 52.69992 90)
			(size 1.8034 0.508)
			(layers "F.Cu" "F.Mask" "F.Paste")
			(net "M_H_BG<1>")
		)
		(pad "208" smd rect
			(at 4.59994 53.550058 90)
			(size 1.8034 0.508)
			(layers "F.Cu" "F.Mask" "F.Paste")
			(net "M_H_ALERT_N")
		)
		(pad "209" smd rect
			(at 4.59994 54.399942 90)
			(size 1.8034 0.508)
			(layers "F.Cu" "F.Mask" "F.Paste")
			(net "PVDDQ_GHJ")
		)
		(pad "210" smd rect
			(at 4.59994 55.25008 90)
			(size 1.8034 0.508)
			(layers "F.Cu" "F.Mask" "F.Paste")
			(net "M_H_MA<11>")
		)
		(pad "211" smd rect
			(at 4.59994 56.099964 90)
			(size 1.8034 0.508)
			(layers "F.Cu" "F.Mask" "F.Paste")
			(net "M_H_MA<7>")
		)
		(pad "212" smd rect
			(at 4.59994 56.950102 90)
			(size 1.8034 0.508)
			(layers "F.Cu" "F.Mask" "F.Paste")
			(net "PVDDQ_GHJ")
		)
		(pad "213" smd rect
			(at 4.59994 57.799986 90)
			(size 1.8034 0.508)
			(layers "F.Cu" "F.Mask" "F.Paste")
			(net "M_H_MA<5>")
		)
		(pad "214" smd rect
			(at 4.59994 58.650124 90)
			(size 1.8034 0.508)
			(layers "F.Cu" "F.Mask" "F.Paste")
			(net "M_H_MA<4>")
		)
		(pad "215" smd rect
			(at 4.59994 59.500008 90)
			(size 1.8034 0.508)
			(layers "F.Cu" "F.Mask" "F.Paste")
			(net "PVDDQ_GHJ")
		)
		(pad "216" smd rect
			(at 4.59994 60.349892 90)
			(size 1.8034 0.508)
			(layers "F.Cu" "F.Mask" "F.Paste")
			(net "M_H_MA<2>")
		)
		(pad "217" smd rect
			(at 4.59994 61.20003 90)
			(size 1.8034 0.508)
			(layers "F.Cu" "F.Mask" "F.Paste")
			(net "PVDDQ_GHJ")
		)
		(pad "218" smd rect
			(at 4.59994 62.049914 90)
			(size 1.8034 0.508)
			(layers "F.Cu" "F.Mask" "F.Paste")
			(net "M_H_CLK_DP<1>")
		)
		(pad "219" smd rect
			(at 4.59994 62.900052 90)
			(size 1.8034 0.508)
			(layers "F.Cu" "F.Mask" "F.Paste")
			(net "M_H_CLK_DN<1>")
		)
		(pad "220" smd rect
			(at 4.59994 63.749936 90)
			(size 1.8034 0.508)
			(layers "F.Cu" "F.Mask" "F.Paste")
			(net "PVDDQ_GHJ")
		)
		(pad "221" smd rect
			(at 4.59994 64.600074 90)
			(size 1.8034 0.508)
			(layers "F.Cu" "F.Mask" "F.Paste")
			(net "PVTT_GHJ")
		)
		(pad "222" smd rect
			(at 4.59994 70.550024 90)
			(size 1.8034 0.508)
			(layers "F.Cu" "F.Mask" "F.Paste")
			(net "M_H_PAR")
		)
		(pad "223" smd rect
			(at 4.59994 71.399908 90)
			(size 1.8034 0.508)
			(layers "F.Cu" "F.Mask" "F.Paste")
			(net "PVDDQ_GHJ")
		)
		(pad "224" smd rect
			(at 4.59994 72.250046 90)
			(size 1.8034 0.508)
			(layers "F.Cu" "F.Mask" "F.Paste")
			(net "M_H_BA<1>")
		)
		(pad "225" smd rect
			(at 4.59994 73.09993 90)
			(size 1.8034 0.508)
			(layers "F.Cu" "F.Mask" "F.Paste")
			(net "M_H_MA<10>")
		)
		(pad "226" smd rect
			(at 4.59994 73.950068 90)
			(size 1.8034 0.508)
			(layers "F.Cu" "F.Mask" "F.Paste")
			(net "PVDDQ_GHJ")
		)
		(pad "227" smd rect
			(at 4.59994 74.799952 90)
			(size 1.8034 0.508)
			(layers "F.Cu" "F.Mask" "F.Paste")
			(net "TP_CH_H_DIMM_H0_RFU_1")
		)
		(pad "228" smd rect
			(at 4.59994 75.65009 90)
			(size 1.8034 0.508)
			(layers "F.Cu" "F.Mask" "F.Paste")
			(net "M_H_MA<14>")
		)
		(pad "229" smd rect
			(at 4.59994 76.499974 90)
			(size 1.8034 0.508)
			(layers "F.Cu" "F.Mask" "F.Paste")
			(net "PVDDQ_GHJ")
		)
		(pad "230" smd rect
			(at 4.59994 77.350112 90)
			(size 1.8034 0.508)
			(layers "F.Cu" "F.Mask" "F.Paste")
			(net "FM_ADR_COMPLETE_GHJ_N")
		)
		(pad "231" smd rect
			(at 4.59994 78.199996 90)
			(size 1.8034 0.508)
			(layers "F.Cu" "F.Mask" "F.Paste")
			(net "PVDDQ_GHJ")
		)
		(pad "232" smd rect
			(at 4.59994 79.04988 90)
			(size 1.8034 0.508)
			(layers "F.Cu" "F.Mask" "F.Paste")
			(net "M_H_MA<13>")
		)
		(pad "233" smd rect
			(at 4.59994 79.900018 90)
			(size 1.8034 0.508)
			(layers "F.Cu" "F.Mask" "F.Paste")
			(net "PVDDQ_GHJ")
		)
		(pad "234" smd rect
			(at 4.59994 80.749902 90)
			(size 1.8034 0.508)
			(layers "F.Cu" "F.Mask" "F.Paste")
			(net "M_H_MA<17>")
		)
		(pad "235" smd rect
			(at 4.59994 81.60004 90)
			(size 1.8034 0.508)
			(layers "F.Cu" "F.Mask" "F.Paste")
			(net "M_H_C<2>")
		)
		(pad "236" smd rect
			(at 4.59994 82.449924 90)
			(size 1.8034 0.508)
			(layers "F.Cu" "F.Mask" "F.Paste")
			(net "PVDDQ_GHJ")
		)
		(pad "237" smd rect
			(at 4.59994 83.300062 90)
			(size 1.8034 0.508)
			(layers "F.Cu" "F.Mask" "F.Paste")
			(net "M_H_CS_N<3>")
		)
		(pad "238" smd rect
			(at 4.59994 84.149946 90)
			(size 1.8034 0.508)
			(layers "F.Cu" "F.Mask" "F.Paste")
			(net "GND")
		)
		(pad "239" smd rect
			(at 4.59994 85.000084 90)
			(size 1.8034 0.508)
			(layers "F.Cu" "F.Mask" "F.Paste")
			(net "GND")
		)
		(pad "240" smd rect
			(at 4.59994 85.849968 90)
			(size 1.8034 0.508)
			(layers "F.Cu" "F.Mask" "F.Paste")
			(net "M_H_DQ<36>")
		)
		(pad "241" smd rect
			(at 4.59994 86.700106 90)
			(size 1.8034 0.508)
			(layers "F.Cu" "F.Mask" "F.Paste")
			(net "GND")
		)
		(pad "242" smd rect
			(at 4.59994 87.54999 90)
			(size 1.8034 0.508)
			(layers "F.Cu" "F.Mask" "F.Paste")
			(net "M_H_DQ<32>")
		)
		(pad "243" smd rect
			(at 4.59994 88.399874 90)
			(size 1.8034 0.508)
			(layers "F.Cu" "F.Mask" "F.Paste")
			(net "GND")
		)
		(pad "244" smd rect
			(at 4.59994 89.250012 90)
			(size 1.8034 0.508)
			(layers "F.Cu" "F.Mask" "F.Paste")
			(net "M_H_DQS_DN<4>")
		)
		(pad "245" smd rect
			(at 4.59994 90.099896 90)
			(size 1.8034 0.508)
			(layers "F.Cu" "F.Mask" "F.Paste")
			(net "M_H_DQS_DP<4>")
		)
		(pad "246" smd rect
			(at 4.59994 90.950034 90)
			(size 1.8034 0.508)
			(layers "F.Cu" "F.Mask" "F.Paste")
			(net "GND")
		)
	)
)
